G04 ================== begin FILE IDENTIFICATION RECORD ==================*
G04 Layout Name:  15968-1a.brd*
G04 Film Name:    L2GND*
G04 File Format:  Gerber RS274X*
G04 File Origin:  Cadence Allegro 16.5-S058*
G04 Origin Date:  Fri Oct 14 10:23:38 2016*
G04 *
G04 Layer:  VIA CLASS/L2GND*
G04 Layer:  PIN/L2GND*
G04 Layer:  ETCH/L2GND*
G04 Layer:  DRAWING FORMAT/LAYER_PCB_STORY*
G04 Layer:  DRAWING FORMAT/LAYER_L2GND*
G04 *
G04 Offset:    (0.00 0.00)*
G04 Mirror:    No*
G04 Mode:      Negative*
G04 Rotation:  0*
G04 FullContactRelief:  No*
G04 UndefLineWidth:     6.00*
G04 ================== end FILE IDENTIFICATION RECORD ====================*
%FSLAX35Y35*MOIN*%
%IR0*IPPOS*OFA0.00000B0.00000*MIA0B0*SFA1.00000B1.00000*%
%AMMACRO12*
4,1,16,.0821,-.02,
.07738,-.033953,
.070308,-.046874,
.061101,-.058371,
.050036,-.068094,
.037452,-.075748,
.023729,-.081101,
.02,-.0821,
.02,-.08724,
.034845,-.082442,
.048632,-.075138,
.060941,-.065552,
.071398,-.053974,
.079685,-.040756,
.085552,-.026299,
.08724,-.02,
.0821,-.02,
0.0*
4,1,16,-.02,-.0821,
-.033953,-.07738,
-.046874,-.070308,
-.058371,-.061101,
-.068094,-.050036,
-.075748,-.037452,
-.081101,-.023729,
-.0821,-.02,
-.08724,-.02,
-.082442,-.034845,
-.075138,-.048632,
-.065552,-.060941,
-.053974,-.071398,
-.040756,-.079685,
-.026299,-.085552,
-.02,-.08724,
-.02,-.0821,
0.0*
4,1,16,-.0821,.02,
-.07738,.033953,
-.070308,.046874,
-.061101,.058371,
-.050036,.068094,
-.037452,.075748,
-.023729,.081101,
-.02,.0821,
-.02,.08724,
-.034845,.082442,
-.048632,.075138,
-.060941,.065552,
-.071398,.053974,
-.079685,.040756,
-.085552,.026299,
-.08724,.02,
-.0821,.02,
0.0*
4,1,16,.02,.0821,
.033953,.07738,
.046874,.070308,
.058371,.061101,
.068094,.050036,
.075748,.037452,
.081101,.023729,
.0821,.02,
.08724,.02,
.082442,.034845,
.075138,.048632,
.065552,.060941,
.053974,.071398,
.040756,.079685,
.026299,.085552,
.02,.08724,
.02,.0821,
0.0*
%
%ADD12MACRO12*%
%ADD14C,.03*%
%ADD11C,.032*%
%ADD17C,.056*%
%AMMACRO15*
4,1,15,.00398,.00044,
.003999,.000208,
.004004,-.000025,
.003996,-.000258,
.00398,-.00044,
.00483,-.00129,
.004897,-.001007,
.004947,-.000721,
.004981,-.000432,
.004997,-.000141,
.004997,.000149,
.00498,.00044,
.004946,.000729,
.004895,.001015,
.00483,.00129,
.00398,.00044,
90.*
4,1,15,.00044,-.00398,
.000208,-.003999,
-.000025,-.004004,
-.000258,-.003996,
-.00044,-.00398,
-.00129,-.00483,
-.001007,-.004897,
-.000721,-.004947,
-.000432,-.004981,
-.000141,-.004997,
.000149,-.004997,
.00044,-.00498,
.000729,-.004946,
.001015,-.004895,
.00129,-.00483,
.00044,-.00398,
90.*
4,1,15,-.00398,-.00044,
-.003999,-.000208,
-.004004,.000025,
-.003996,.000258,
-.00398,.00044,
-.00483,.00129,
-.004897,.001007,
-.004947,.000721,
-.004981,.000432,
-.004997,.000141,
-.004997,-.000149,
-.00498,-.00044,
-.004946,-.000729,
-.004895,-.001015,
-.00483,-.00129,
-.00398,-.00044,
90.*
4,1,15,-.00044,.00398,
-.000208,.003999,
.000025,.004004,
.000258,.003996,
.00044,.00398,
.00129,.00483,
.001007,.004897,
.000721,.004947,
.000432,.004981,
.000141,.004997,
-.000149,.004997,
-.00044,.00498,
-.000729,.004946,
-.001015,.004895,
-.00129,.00483,
-.00044,.00398,
90.*
%
%ADD15MACRO15*%
%AMMACRO13*
4,1,15,.00398,.00044,
.003999,.000208,
.004004,-.000025,
.003996,-.000258,
.00398,-.00044,
.00483,-.00129,
.004897,-.001007,
.004947,-.000721,
.004981,-.000432,
.004997,-.000141,
.004997,.000149,
.00498,.00044,
.004946,.000729,
.004895,.001015,
.00483,.00129,
.00398,.00044,
0.0*
4,1,15,.00044,-.00398,
.000208,-.003999,
-.000025,-.004004,
-.000258,-.003996,
-.00044,-.00398,
-.00129,-.00483,
-.001007,-.004897,
-.000721,-.004947,
-.000432,-.004981,
-.000141,-.004997,
.000149,-.004997,
.00044,-.00498,
.000729,-.004946,
.001015,-.004895,
.00129,-.00483,
.00044,-.00398,
0.0*
4,1,15,-.00398,-.00044,
-.003999,-.000208,
-.004004,.000025,
-.003996,.000258,
-.00398,.00044,
-.00483,.00129,
-.004897,.001007,
-.004947,.000721,
-.004981,.000432,
-.004997,.000141,
-.004997,-.000149,
-.00498,-.00044,
-.004946,-.000729,
-.004895,-.001015,
-.00483,-.00129,
-.00398,-.00044,
0.0*
4,1,15,-.00044,.00398,
-.000208,.003999,
.000025,.004004,
.000258,.003996,
.00044,.00398,
.00129,.00483,
.001007,.004897,
.000721,.004947,
.000432,.004981,
.000141,.004997,
-.000149,.004997,
-.00044,.00498,
-.000729,.004946,
-.001015,.004895,
-.00129,.00483,
-.00044,.00398,
0.0*
%
%ADD13MACRO13*%
%ADD20C,.111*%
%ADD16C,.121*%
%ADD10C,.114*%
%AMMACRO21*
4,1,14,.0447,.02349,
.0481,.015371,
.050038,.006785,
.050456,-.002007,
.049341,-.010738,
.046727,-.019143,
.0447,-.02349,
.04839,-.02718,
.052375,-.018364,
.054768,-.00899,
.055497,.000656,
.05454,.010283,
.051926,.019598,
.04839,.02718,
.0447,.02349,
90.*
4,1,14,.02349,-.0447,
.015371,-.0481,
.006785,-.050038,
-.002007,-.050456,
-.010738,-.049341,
-.019143,-.046727,
-.02349,-.0447,
-.02718,-.04839,
-.018364,-.052375,
-.00899,-.054768,
.000656,-.055497,
.010283,-.05454,
.019598,-.051926,
.02718,-.04839,
.02349,-.0447,
90.*
4,1,14,-.0447,-.02349,
-.0481,-.015371,
-.050038,-.006785,
-.050456,.002007,
-.049341,.010738,
-.046727,.019143,
-.0447,.02349,
-.04839,.02718,
-.052375,.018364,
-.054768,.00899,
-.055497,-.000656,
-.05454,-.010283,
-.051926,-.019598,
-.04839,-.02718,
-.0447,-.02349,
90.*
4,1,14,-.02349,.0447,
-.015371,.0481,
-.006785,.050038,
.002007,.050456,
.010738,.049341,
.019143,.046727,
.02349,.0447,
.02718,.04839,
.018364,.052375,
.00899,.054768,
-.000656,.055497,
-.010283,.05454,
-.019598,.051926,
-.02718,.04839,
-.02349,.0447,
90.*
%
%ADD21MACRO21*%
%AMMACRO19*
4,1,15,.00398,.00044,
.003999,.000208,
.004004,-.000025,
.003996,-.000258,
.00398,-.00044,
.00483,-.00129,
.004897,-.001007,
.004947,-.000721,
.004981,-.000432,
.004997,-.000141,
.004997,.000149,
.00498,.00044,
.004946,.000729,
.004895,.001015,
.00483,.00129,
.00398,.00044,
270.*
4,1,15,.00044,-.00398,
.000208,-.003999,
-.000025,-.004004,
-.000258,-.003996,
-.00044,-.00398,
-.00129,-.00483,
-.001007,-.004897,
-.000721,-.004947,
-.000432,-.004981,
-.000141,-.004997,
.000149,-.004997,
.00044,-.00498,
.000729,-.004946,
.001015,-.004895,
.00129,-.00483,
.00044,-.00398,
270.*
4,1,15,-.00398,-.00044,
-.003999,-.000208,
-.004004,.000025,
-.003996,.000258,
-.00398,.00044,
-.00483,.00129,
-.004897,.001007,
-.004947,.000721,
-.004981,.000432,
-.004997,.000141,
-.004997,-.000149,
-.00498,-.00044,
-.004946,-.000729,
-.004895,-.001015,
-.00483,-.00129,
-.00398,-.00044,
270.*
4,1,15,-.00044,.00398,
-.000208,.003999,
.000025,.004004,
.000258,.003996,
.00044,.00398,
.00129,.00483,
.001007,.004897,
.000721,.004947,
.000432,.004981,
.000141,.004997,
-.000149,.004997,
-.00044,.00498,
-.000729,.004946,
-.001015,.004895,
-.00129,.00483,
-.00044,.00398,
270.*
%
%ADD19MACRO19*%
%AMMACRO18*
4,1,19,.02172,.00757,
.022123,.006294,
.022452,.004997,
.022705,.003683,
.02288,.002357,
.022979,.001023,
.022999,-.000315,
.022942,-.001652,
.022807,-.002983,
.022595,-.004304,
.022307,-.005611,
.021943,-.006898,
.02172,-.00757,
.02556,-.01142,
.027155,-.006808,
.027924,-.001989,
.027846,.00289,
.026921,.007681,
.02556,.01142,
.02172,.00757,
0.0*
4,1,19,.00757,-.02172,
.006294,-.022123,
.004997,-.022452,
.003683,-.022705,
.002357,-.02288,
.001023,-.022979,
-.000315,-.022999,
-.001652,-.022942,
-.002983,-.022807,
-.004304,-.022595,
-.005611,-.022307,
-.006898,-.021943,
-.00757,-.02172,
-.01142,-.02556,
-.006808,-.027155,
-.001989,-.027924,
.00289,-.027846,
.007681,-.026921,
.01142,-.02556,
.00757,-.02172,
0.0*
4,1,19,-.02172,-.00757,
-.022123,-.006294,
-.022452,-.004997,
-.022705,-.003683,
-.02288,-.002357,
-.022979,-.001023,
-.022999,.000315,
-.022942,.001652,
-.022807,.002983,
-.022595,.004304,
-.022307,.005611,
-.021943,.006898,
-.02172,.00757,
-.02556,.01142,
-.027155,.006808,
-.027924,.001989,
-.027846,-.00289,
-.026921,-.007681,
-.02556,-.01142,
-.02172,-.00757,
0.0*
4,1,19,-.00757,.02172,
-.006294,.022123,
-.004997,.022452,
-.003683,.022705,
-.002357,.02288,
-.001023,.022979,
.000315,.022999,
.001652,.022942,
.002983,.022807,
.004304,.022595,
.005611,.022307,
.006898,.021943,
.00757,.02172,
.01142,.02556,
.006808,.027155,
.001989,.027924,
-.00289,.027846,
-.007681,.026921,
-.01142,.02556,
-.00757,.02172,
0.0*
%
%ADD18MACRO18*%
%ADD22C,.02*%
%ADD23C,.006*%
%ADD24C,.11004*%
%ADD25C,.11704*%
%ADD26C,.12524*%
G75*
%LPD*%
G75*
G36*
G01X-6000Y-79346D02*
X621748D01*
Y247988D01*
X-6000D01*
Y-79346D01*
G37*
%LPC*%
G75*
G36*
G01X3004Y238051D02*
G02X3937Y238984I933J0D01*
G01X179423D01*
G02X179669Y238269I0J-400D01*
G03X178662Y235208I1789J-2285D01*
G01X178682Y235134D01*
X176534Y230840D01*
X176463Y230812D01*
G03X180314Y228886I1055J-2703D01*
G01X180294Y228960D01*
X182441Y233253D01*
X182513Y233281D01*
G03X183247Y238269I-1055J2703D01*
G02X183493Y238984I246J315D01*
G01X187298D01*
G02X187544Y238269I0J-400D01*
G03X188276Y233281I1789J-2285D01*
G01X188348Y233253D01*
X190493Y228960D01*
X190472Y228886D01*
G03X194325Y230812I2796J-777D01*
G01X194253Y230840D01*
X192108Y235132D01*
X192129Y235207D01*
G03X191122Y238269I-2796J777D01*
G02X191368Y238984I246J315D01*
G01X210918D01*
G02X211164Y238269I0J-400D01*
G03X210157Y235206I1789J-2285D01*
G01X210178Y235132D01*
X208033Y230840D01*
X207961Y230812D01*
G03X211814Y228886I1057J-2703D01*
G01X211793Y228960D01*
X213938Y233253D01*
X214010Y233281D01*
G03X214742Y238269I-1057J2703D01*
G02X214988Y238984I246J315D01*
G01X226668D01*
G02X226914Y238269I0J-400D01*
G03X225907Y235208I1789J-2285D01*
G01X225927Y235134D01*
X223779Y230840D01*
X223708Y230812D01*
G03X227559Y228886I1055J-2703D01*
G01X227539Y228960D01*
X229686Y233253D01*
X229758Y233281D01*
G03X230492Y238269I-1055J2703D01*
G02X230738Y238984I246J315D01*
G01X242413D01*
G02X242659Y238269I0J-400D01*
G03X241652Y235206I1789J-2285D01*
G01X241673Y235132D01*
X239528Y230840D01*
X239456Y230812D01*
G03X243309Y228886I1057J-2703D01*
G01X243288Y228960D01*
X245433Y233253D01*
X245505Y233281D01*
G03X246237Y238269I-1057J2703D01*
G02X246483Y238984I246J315D01*
G01X250288D01*
G02X250534Y238269I0J-400D01*
G03X251266Y233281I1789J-2285D01*
G01X251338Y233253D01*
X253483Y228960D01*
X253462Y228886D01*
G03X257315Y230812I2796J-777D01*
G01X257243Y230840D01*
X255098Y235132D01*
X255119Y235207D01*
G03X254112Y238269I-2796J777D01*
G02X254358Y238984I246J315D01*
G01X266038D01*
G02X266284Y238269I0J-400D01*
G03X265277Y235208I1789J-2285D01*
G01X265297Y235134D01*
X263149Y230840D01*
X263078Y230812D01*
G03X266929Y228886I1055J-2703D01*
G01X266909Y228960D01*
X269056Y233253D01*
X269128Y233281D01*
G03X269862Y238269I-1055J2703D01*
G02X270108Y238984I246J315D01*
G01X281783D01*
G02X282029Y238269I0J-400D01*
G03X281022Y235206I1789J-2285D01*
G01X281043Y235132D01*
X278898Y230840D01*
X278826Y230812D01*
G03X282679Y228886I1057J-2703D01*
G01X282658Y228960D01*
X284803Y233253D01*
X284875Y233281D01*
G03X285607Y238269I-1057J2703D01*
G02X285853Y238984I246J315D01*
G01X297533D01*
G02X297779Y238269I0J-400D01*
G03X296772Y235208I1789J-2285D01*
G01X296792Y235134D01*
X294644Y230840D01*
X294573Y230812D01*
G03X298424Y228886I1055J-2703D01*
G01X298404Y228960D01*
X300551Y233253D01*
X300623Y233281D01*
G03X301357Y238269I-1055J2703D01*
G02X301603Y238984I246J315D01*
G01X313278D01*
G02X313524Y238269I0J-400D01*
G03X312517Y235206I1789J-2285D01*
G01X312538Y235132D01*
X310393Y230840D01*
X310321Y230812D01*
G03X314174Y228886I1057J-2703D01*
G01X314153Y228960D01*
X316298Y233253D01*
X316370Y233281D01*
G03X317102Y238269I-1057J2703D01*
G02X317348Y238984I246J315D01*
G01X329028D01*
G02X329274Y238269I0J-400D01*
G03X329408Y233600I1789J-2285D01*
G01X329450Y233571D01*
X332100Y228268D01*
X332098Y228217D01*
G03X336652Y230493I2900J-108D01*
G01X336610Y230522D01*
X333961Y235824D01*
X333963Y235876D01*
G03X332852Y238269I-2900J108D01*
G02X333098Y238984I246J315D01*
G01X344778D01*
G02X345024Y238269I0J-400D01*
G03X345158Y233600I1789J-2285D01*
G01X345200Y233571D01*
X347850Y228268D01*
X347848Y228217D01*
G03X352402Y230493I2900J-108D01*
G01X352360Y230522D01*
X349711Y235824D01*
X349713Y235876D01*
G03X348602Y238269I-2900J108D01*
G02X348848Y238984I246J315D01*
G01X360523D01*
G02X360769Y238269I0J-400D01*
G03X360920Y233588I1789J-2285D01*
G01X360963Y233559D01*
X363601Y228286D01*
X363599Y228234D01*
G03X368136Y230504I2899J-125D01*
G01X368093Y230534D01*
X365455Y235807D01*
X365457Y235859D01*
G03X364347Y238269I-2899J125D01*
G02X364593Y238984I246J315D01*
G01X376273D01*
G02X376519Y238269I0J-400D01*
G03X376653Y233600I1789J-2285D01*
G01X376695Y233571D01*
X379345Y228268D01*
X379343Y228217D01*
G03X383897Y230493I2900J-108D01*
G01X383855Y230522D01*
X381206Y235824D01*
X381208Y235876D01*
G03X380097Y238269I-2900J108D01*
G02X380343Y238984I246J315D01*
G01X392018D01*
G02X392264Y238269I0J-400D01*
G03X392415Y233588I1789J-2285D01*
G01X392458Y233559D01*
X395096Y228286D01*
X395094Y228234D01*
G03X399631Y230504I2899J-125D01*
G01X399588Y230534D01*
X396950Y235807D01*
X396952Y235859D01*
G03X395842Y238269I-2899J125D01*
G02X396088Y238984I246J315D01*
G01X407768D01*
G02X408014Y238269I0J-400D01*
G03X408148Y233600I1789J-2285D01*
G01X408190Y233571D01*
X410840Y228268D01*
X410838Y228217D01*
G03X415392Y230493I2900J-108D01*
G01X415350Y230522D01*
X412701Y235824D01*
X412703Y235876D01*
G03X411592Y238269I-2900J108D01*
G02X411838Y238984I246J315D01*
G01X423518D01*
G02X423764Y238269I0J-400D01*
G03X423898Y233600I1789J-2285D01*
G01X423940Y233571D01*
X426590Y228268D01*
X426588Y228217D01*
G03X431142Y230493I2900J-108D01*
G01X431100Y230522D01*
X428451Y235824D01*
X428453Y235876D01*
G03X427342Y238269I-2900J108D01*
G02X427588Y238984I246J315D01*
G01X439263D01*
G02X439509Y238269I0J-400D01*
G03X439660Y233588I1789J-2285D01*
G01X439703Y233559D01*
X442341Y228286D01*
X442339Y228234D01*
G03X446876Y230504I2899J-125D01*
G01X446833Y230534D01*
X444195Y235807D01*
X444197Y235859D01*
G03X443087Y238269I-2899J125D01*
G02X443333Y238984I246J315D01*
G01X602308D01*
G02X602966Y238711I-1J-933D01*
G01X612471Y229206D01*
G02X612744Y228548I-660J-659D01*
G01Y163248D01*
G02X611811Y162315I-933J0D01*
G01X562598D01*
G03X562366Y162311I4J-6941D01*
G01X561355D01*
X561221Y162177D01*
X561163Y162165D01*
G03X555807Y156809I1435J-6791D01*
G01X555795Y156751D01*
X555661Y156617D01*
Y155606D01*
G03X555657Y155374I6937J-236D01*
G01Y9504D01*
G02X555384Y8845I-933J0D01*
G01X549817Y3277D01*
G02X549159Y3004I-660J660D01*
G01X544015D01*
G03X543783Y3000I4J-6941D01*
G01X542773D01*
X542640Y2866D01*
X542582Y2854D01*
G03X537225Y-2503I1434J-6791D01*
G01X537213Y-2561D01*
X537079Y-2694D01*
Y-3704D01*
G03X537075Y-3936I6937J-236D01*
G01Y-59195D01*
X443673D01*
Y-42636D01*
G03X443669Y-42467I-3791J-5D01*
G01Y-41395D01*
X443326Y-41052D01*
G03X441500Y-39209I-3444J-1586D01*
G01X441469Y-39194D01*
X441125Y-38850D01*
X440052D01*
G03X439883Y-38846I-174J-3787D01*
G01X406219D01*
G03X406050Y-38850I5J-3791D01*
G01X404977D01*
X404633Y-39194D01*
X404602Y-39209D01*
G03X402792Y-41021I1620J-3428D01*
G01X402777Y-41052D01*
X402433Y-41395D01*
Y-42467D01*
G03X402429Y-42637I3787J-174D01*
G01Y-58400D01*
X190248D01*
Y-52873D01*
G03X190244Y-52628I-7728J-4D01*
G01Y-51631D01*
X190128Y-51515D01*
X190117Y-51454D01*
G03X174922I-7598J-1420D01*
G01X174911Y-51515D01*
X174795Y-51631D01*
Y-52628D01*
G03X174791Y-52873I7724J-249D01*
G01Y-58400D01*
X75957D01*
Y-3936D01*
G03X75953Y-3704I-6941J-4D01*
G01Y-2694D01*
X75819Y-2560D01*
X75807Y-2502D01*
G03X70451Y2854I-6791J-1435D01*
G01X70393Y2866D01*
X70259Y3000D01*
X69249D01*
G03X69017Y3004I-236J-6937D01*
G01X9503D01*
G02X8845Y3277I1J933D01*
G01X3277Y8845D01*
G02X3004Y9503I660J659D01*
G01Y238051D01*
G37*
%LPD*%
G75*
G36*
G01X530994Y-35788D02*
G02Y-40212I0J-2212D01*
G01X524993D01*
G02X524994Y-35788I1J2212D01*
G01X530994D01*
G37*
G36*
G01X453736Y102940D02*
G02Y107362I0J2211D01*
G01X457246D01*
G02X457245Y102940I-1J-2211D01*
G01X453736D01*
G37*
G36*
G01X459302Y52267D02*
G02X463724I2211J0D01*
G01Y48757D01*
G02X459302Y48758I-2211J1D01*
G01Y52267D01*
G37*
G36*
G01X449170Y91719D02*
G02X453592I2211J0D01*
G01Y88209D01*
G02X449170Y88210I-2211J1D01*
G01Y91719D01*
G37*
G36*
G01X350621Y-48676D02*
G02Y-44252I0J2212D01*
G01X354622D01*
G02X354621Y-48676I-1J-2212D01*
G01X350621D01*
G37*
G36*
G01X360821D02*
G02Y-44252I0J2212D01*
G01X364822D01*
G02X364821Y-48676I-1J-2212D01*
G01X360821D01*
G37*
G36*
G01X381221D02*
G02Y-44252I0J2212D01*
G01X385222D01*
G02X385221Y-48676I-1J-2212D01*
G01X381221D01*
G37*
G36*
G01X371021D02*
G02Y-44252I0J2212D01*
G01X375022D01*
G02X375021Y-48676I-1J-2212D01*
G01X371021D01*
G37*
G36*
G01X391421D02*
G02Y-44252I0J2212D01*
G01X395422D01*
G02X395421Y-48676I-1J-2212D01*
G01X391421D01*
G37*
G36*
G01X396642Y-38690D02*
G02Y-34268I0J2211D01*
G01X400643D01*
G02X400642Y-38690I-1J-2211D01*
G01X396642D01*
G37*
G36*
G01X386442D02*
G02Y-34268I0J2211D01*
G01X390443D01*
G02X390442Y-38690I-1J-2211D01*
G01X386442D01*
G37*
G36*
G01X376242D02*
G02Y-34268I0J2211D01*
G01X380243D01*
G02X380242Y-38690I-1J-2211D01*
G01X376242D01*
G37*
G36*
G01X366042D02*
G02Y-34268I0J2211D01*
G01X370043D01*
G02X370042Y-38690I-1J-2211D01*
G01X366042D01*
G37*
G36*
G01X355842D02*
G02Y-34268I0J2211D01*
G01X359843D01*
G02X359842Y-38690I-1J-2211D01*
G01X355842D01*
G37*
G36*
G01X320021Y-48676D02*
G02Y-44252I0J2212D01*
G01X324022D01*
G02X324021Y-48676I-1J-2212D01*
G01X320021D01*
G37*
G36*
G01X334221Y-44252D02*
G02Y-48676I0J-2212D01*
G01X330220D01*
G02X330221Y-44252I1J2212D01*
G01X334221D01*
G37*
G36*
G01X340421Y-48676D02*
G02Y-44252I0J2212D01*
G01X344422D01*
G02X344421Y-48676I-1J-2212D01*
G01X340421D01*
G37*
G36*
G01X345642Y-38690D02*
G02Y-34268I0J2211D01*
G01X349643D01*
G02X349642Y-38690I-1J-2211D01*
G01X345642D01*
G37*
G36*
G01X335442D02*
G02Y-34268I0J2211D01*
G01X339443D01*
G02X339442Y-38690I-1J-2211D01*
G01X335442D01*
G37*
G36*
G01X325242D02*
G02Y-34268I0J2211D01*
G01X329243D01*
G02X329242Y-38690I-1J-2211D01*
G01X325242D01*
G37*
G36*
G01X432368Y213097D02*
X432439Y213125D01*
X434587Y217419D01*
X434567Y217493D01*
G02X438418Y215566I2796J776D01*
G01X438346Y215538D01*
X436199Y211245D01*
X436219Y211171D01*
G02X432368Y213097I-2796J-777D01*
G37*
G36*
G01X416621D02*
X416693Y213125D01*
X418838Y217417D01*
X418817Y217491D01*
G02X422670Y215566I2796J778D01*
G01X422598Y215538D01*
X420453Y211245D01*
X420474Y211171D01*
G02X416621Y213097I-2796J-777D01*
G37*
G36*
G01X400873D02*
X400944Y213125D01*
X403092Y217419D01*
X403072Y217493D01*
G02X406923Y215566I2796J776D01*
G01X406851Y215538D01*
X404704Y211245D01*
X404724Y211171D01*
G02X400873Y213097I-2796J-777D01*
G37*
G36*
G01X385126D02*
X385198Y213125D01*
X387343Y217417D01*
X387322Y217491D01*
G02X391175Y215566I2796J778D01*
G01X391103Y215538D01*
X388958Y211245D01*
X388979Y211171D01*
G02X385126Y213097I-2796J-777D01*
G37*
G36*
G01X369376D02*
X369448Y213125D01*
X371593Y217417D01*
X371572Y217491D01*
G02X375425Y215566I2796J778D01*
G01X375353Y215538D01*
X373208Y211245D01*
X373229Y211171D01*
G02X369376Y213097I-2796J-777D01*
G37*
G36*
G01X353628D02*
X353699Y213125D01*
X355847Y217419D01*
X355827Y217493D01*
G02X359678Y215566I2796J776D01*
G01X359606Y215538D01*
X357459Y211245D01*
X357479Y211171D01*
G02X353628Y213097I-2796J-777D01*
G37*
G36*
G01X337881D02*
X337953Y213125D01*
X340098Y217417D01*
X340077Y217491D01*
G02X343930Y215566I2796J778D01*
G01X343858Y215538D01*
X341713Y211245D01*
X341734Y211171D01*
G02X337881Y213097I-2796J-777D01*
G37*
G36*
G01X322133D02*
X322204Y213125D01*
X324352Y217419D01*
X324332Y217493D01*
G02X328183Y215566I2796J776D01*
G01X328111Y215538D01*
X325964Y211245D01*
X325984Y211171D01*
G02X322133Y213097I-2796J-777D01*
G37*
G36*
G01X304647Y211171D02*
X304667Y211245D01*
X302520Y215538D01*
X302448Y215566D01*
G02X306299Y217493I1055J2703D01*
G01X306279Y217418D01*
X308427Y213125D01*
X308499Y213097D01*
G02X304647Y211171I-1056J-2703D01*
G37*
G36*
G01X288897D02*
X288918Y211245D01*
X286773Y215538D01*
X286701Y215566D01*
G02X290554Y217492I1057J2703D01*
G01X290533Y217417D01*
X292678Y213125D01*
X292750Y213097D01*
G02X288897Y211171I-1057J-2703D01*
G37*
G36*
G01X273147D02*
X273168Y211245D01*
X271023Y215538D01*
X270951Y215566D01*
G02X274804Y217492I1057J2703D01*
G01X274783Y217417D01*
X276928Y213125D01*
X277000Y213097D01*
G02X273147Y211171I-1057J-2703D01*
G37*
G36*
G01X257402D02*
X257422Y211245D01*
X255275Y215538D01*
X255203Y215566D01*
G02X259054Y217493I1055J2703D01*
G01X259034Y217418D01*
X261182Y213125D01*
X261254Y213097D01*
G02X257402Y211171I-1056J-2703D01*
G37*
G36*
G01X233777D02*
X233798Y211245D01*
X231653Y215538D01*
X231581Y215566D01*
G02X235434Y217492I1057J2703D01*
G01X235413Y217417D01*
X237558Y213125D01*
X237630Y213097D01*
G02X233777Y211171I-1057J-2703D01*
G37*
G36*
G01X218032D02*
X218052Y211245D01*
X215905Y215538D01*
X215833Y215566D01*
G02X219684Y217493I1055J2703D01*
G01X219664Y217418D01*
X221812Y213125D01*
X221884Y213097D01*
G02X218032Y211171I-1056J-2703D01*
G37*
G36*
G01X203939Y217492D02*
X203918Y217417D01*
X206063Y213125D01*
X206135Y213097D01*
G02X202282Y211171I-1057J-2703D01*
G01X202303Y211245D01*
X200158Y215538D01*
X200086Y215566D01*
G02X203939Y217492I1057J2703D01*
G37*
G36*
G01X186450Y215566D02*
X186378Y215538D01*
X184233Y211245D01*
X184254Y211171D01*
G02X180401Y213097I-2796J-777D01*
G01X180473Y213125D01*
X182618Y217417D01*
X182597Y217491D01*
G02X186450Y215566I2796J778D01*
G37*
G36*
G01X442442Y148886D02*
X442462Y148960D01*
X440315Y153253D01*
X440243Y153281D01*
G02X444094Y155208I1055J2703D01*
G01X444074Y155133D01*
X446222Y150840D01*
X446294Y150812D01*
G02X442442Y148886I-1056J-2703D01*
G37*
G36*
G01X426692D02*
X426713Y148960D01*
X424568Y153253D01*
X424496Y153281D01*
G02X428349Y155207I1057J2703D01*
G01X428328Y155132D01*
X430473Y150840D01*
X430545Y150812D01*
G02X426692Y148886I-1057J-2703D01*
G37*
G36*
G01X410942D02*
X410963Y148960D01*
X408818Y153253D01*
X408746Y153281D01*
G02X412599Y155207I1057J2703D01*
G01X412578Y155132D01*
X414723Y150840D01*
X414795Y150812D01*
G02X410942Y148886I-1057J-2703D01*
G37*
G36*
G01X395197D02*
X395217Y148960D01*
X393070Y153253D01*
X392998Y153281D01*
G02X396849Y155208I1055J2703D01*
G01X396829Y155133D01*
X398977Y150840D01*
X399049Y150812D01*
G02X395197Y148886I-1056J-2703D01*
G37*
G36*
G01X379447D02*
X379468Y148960D01*
X377323Y153253D01*
X377251Y153281D01*
G02X381104Y155207I1057J2703D01*
G01X381083Y155132D01*
X383228Y150840D01*
X383300Y150812D01*
G02X379447Y148886I-1057J-2703D01*
G37*
G36*
G01X363702D02*
X363722Y148960D01*
X361575Y153253D01*
X361503Y153281D01*
G02X365354Y155208I1055J2703D01*
G01X365334Y155133D01*
X367482Y150840D01*
X367554Y150812D01*
G02X363702Y148886I-1056J-2703D01*
G37*
G36*
G01X347952D02*
X347973Y148960D01*
X345828Y153253D01*
X345756Y153281D01*
G02X349609Y155207I1057J2703D01*
G01X349588Y155132D01*
X351733Y150840D01*
X351805Y150812D01*
G02X347952Y148886I-1057J-2703D01*
G37*
G36*
G01X333859Y155207D02*
X333838Y155132D01*
X335983Y150840D01*
X336055Y150812D01*
G02X332202Y148886I-1057J-2703D01*
G01X332223Y148960D01*
X330078Y153253D01*
X330006Y153281D01*
G02X333859Y155207I1057J2703D01*
G37*
G36*
G01X310321Y150812D02*
X310393Y150840D01*
X312538Y155132D01*
X312517Y155206D01*
G02X316370Y153281I2796J778D01*
G01X316298Y153253D01*
X314153Y148960D01*
X314174Y148886D01*
G02X310321Y150812I-2796J-777D01*
G37*
G36*
G01X294573D02*
X294644Y150840D01*
X296792Y155134D01*
X296772Y155208D01*
G02X300623Y153281I2796J776D01*
G01X300551Y153253D01*
X298404Y148960D01*
X298424Y148886D01*
G02X294573Y150812I-2796J-777D01*
G37*
G36*
G01X278826D02*
X278898Y150840D01*
X281043Y155132D01*
X281022Y155206D01*
G02X284875Y153281I2796J778D01*
G01X284803Y153253D01*
X282658Y148960D01*
X282679Y148886D01*
G02X278826Y150812I-2796J-777D01*
G37*
G36*
G01X263078D02*
X263149Y150840D01*
X265297Y155134D01*
X265277Y155208D01*
G02X269128Y153281I2796J776D01*
G01X269056Y153253D01*
X266909Y148960D01*
X266929Y148886D01*
G02X263078Y150812I-2796J-777D01*
G37*
G36*
G01X255119Y155207D02*
X255098Y155132D01*
X257243Y150840D01*
X257315Y150812D01*
G02X253462Y148886I-1057J-2703D01*
G01X253483Y148960D01*
X251338Y153253D01*
X251266Y153281D01*
G02X255119Y155207I1057J2703D01*
G37*
G36*
G01X239456Y150812D02*
X239528Y150840D01*
X241673Y155132D01*
X241652Y155206D01*
G02X245505Y153281I2796J778D01*
G01X245433Y153253D01*
X243288Y148960D01*
X243309Y148886D01*
G02X239456Y150812I-2796J-777D01*
G37*
G36*
G01X223708D02*
X223779Y150840D01*
X225927Y155134D01*
X225907Y155208D01*
G02X229758Y153281I2796J776D01*
G01X229686Y153253D01*
X227539Y148960D01*
X227559Y148886D01*
G02X223708Y150812I-2796J-777D01*
G37*
G36*
G01X207961D02*
X208033Y150840D01*
X210178Y155132D01*
X210157Y155206D01*
G02X214010Y153281I2796J778D01*
G01X213938Y153253D01*
X211793Y148960D01*
X211814Y148886D01*
G02X207961Y150812I-2796J-777D01*
G37*
G36*
G01X190472Y148886D02*
X190493Y148960D01*
X188348Y153253D01*
X188276Y153281D01*
G02X192129Y155207I1057J2703D01*
G01X192108Y155132D01*
X194253Y150840D01*
X194325Y150812D01*
G02X190472Y148886I-1057J-2703D01*
G37*
G36*
G01X182513Y153281D02*
X182441Y153253D01*
X180294Y148960D01*
X180314Y148886D01*
G02X176463Y150812I-2796J-777D01*
G01X176534Y150840D01*
X178682Y155134D01*
X178662Y155208D01*
G02X182513Y153281I2796J776D01*
G37*
G36*
G01X432368Y133097D02*
X432439Y133125D01*
X434587Y137419D01*
X434567Y137493D01*
G02X438418Y135566I2796J776D01*
G01X438346Y135538D01*
X436199Y131245D01*
X436219Y131171D01*
G02X432368Y133097I-2796J-777D01*
G37*
G36*
G01X416621D02*
X416693Y133125D01*
X418838Y137417D01*
X418817Y137491D01*
G02X422670Y135566I2796J778D01*
G01X422598Y135538D01*
X420453Y131245D01*
X420474Y131171D01*
G02X416621Y133097I-2796J-777D01*
G37*
G36*
G01X400873D02*
X400944Y133125D01*
X403092Y137419D01*
X403072Y137493D01*
G02X406923Y135566I2796J776D01*
G01X406851Y135538D01*
X404704Y131245D01*
X404724Y131171D01*
G02X400873Y133097I-2796J-777D01*
G37*
G36*
G01X385126D02*
X385198Y133125D01*
X387343Y137417D01*
X387322Y137491D01*
G02X391175Y135566I2796J778D01*
G01X391103Y135538D01*
X388958Y131245D01*
X388979Y131171D01*
G02X385126Y133097I-2796J-777D01*
G37*
G36*
G01X369376D02*
X369448Y133125D01*
X371593Y137417D01*
X371572Y137491D01*
G02X375425Y135566I2796J778D01*
G01X375353Y135538D01*
X373208Y131245D01*
X373229Y131171D01*
G02X369376Y133097I-2796J-777D01*
G37*
G36*
G01X353628D02*
X353699Y133125D01*
X355847Y137419D01*
X355827Y137493D01*
G02X359678Y135566I2796J776D01*
G01X359606Y135538D01*
X357459Y131245D01*
X357479Y131171D01*
G02X353628Y133097I-2796J-777D01*
G37*
G36*
G01X337881D02*
X337953Y133125D01*
X340098Y137417D01*
X340077Y137491D01*
G02X343930Y135566I2796J778D01*
G01X343858Y135538D01*
X341713Y131245D01*
X341734Y131171D01*
G02X337881Y133097I-2796J-777D01*
G37*
G36*
G01X322133D02*
X322204Y133125D01*
X324352Y137419D01*
X324332Y137493D01*
G02X328183Y135566I2796J776D01*
G01X328111Y135538D01*
X325964Y131245D01*
X325984Y131171D01*
G02X322133Y133097I-2796J-777D01*
G37*
G36*
G01X304647Y131171D02*
X304667Y131245D01*
X302520Y135538D01*
X302448Y135566D01*
G02X306299Y137493I1055J2703D01*
G01X306279Y137418D01*
X308427Y133125D01*
X308499Y133097D01*
G02X304647Y131171I-1056J-2703D01*
G37*
G36*
G01X288897D02*
X288918Y131245D01*
X286773Y135538D01*
X286701Y135566D01*
G02X290554Y137492I1057J2703D01*
G01X290533Y137417D01*
X292678Y133125D01*
X292750Y133097D01*
G02X288897Y131171I-1057J-2703D01*
G37*
G36*
G01X273147D02*
X273168Y131245D01*
X271023Y135538D01*
X270951Y135566D01*
G02X274804Y137492I1057J2703D01*
G01X274783Y137417D01*
X276928Y133125D01*
X277000Y133097D01*
G02X273147Y131171I-1057J-2703D01*
G37*
G36*
G01X257402D02*
X257422Y131245D01*
X255275Y135538D01*
X255203Y135566D01*
G02X259054Y137493I1055J2703D01*
G01X259034Y137418D01*
X261182Y133125D01*
X261254Y133097D01*
G02X257402Y131171I-1056J-2703D01*
G37*
G36*
G01X233777D02*
X233798Y131245D01*
X231653Y135538D01*
X231581Y135566D01*
G02X235434Y137492I1057J2703D01*
G01X235413Y137417D01*
X237558Y133125D01*
X237630Y133097D01*
G02X233777Y131171I-1057J-2703D01*
G37*
G36*
G01X218032D02*
X218052Y131245D01*
X215905Y135538D01*
X215833Y135566D01*
G02X219684Y137493I1055J2703D01*
G01X219664Y137418D01*
X221812Y133125D01*
X221884Y133097D01*
G02X218032Y131171I-1056J-2703D01*
G37*
G36*
G01X203939Y137492D02*
X203918Y137417D01*
X206063Y133125D01*
X206135Y133097D01*
G02X202282Y131171I-1057J-2703D01*
G01X202303Y131245D01*
X200158Y135538D01*
X200086Y135566D01*
G02X203939Y137492I1057J2703D01*
G37*
G36*
G01X186450Y135566D02*
X186378Y135538D01*
X184233Y131245D01*
X184254Y131171D01*
G02X180401Y133097I-2796J-777D01*
G01X180473Y133125D01*
X182618Y137417D01*
X182597Y137491D01*
G02X186450Y135566I2796J778D01*
G37*
G54D24*
X14794Y226306D03*
X542107Y17432D03*
X585785Y228866D03*
G54D25*
X168268Y143189D03*
Y223189D03*
X456258Y143189D03*
Y223189D03*
G54D26*
X561024Y206792D03*
G54D12*
X15748Y128150D03*
X542913D03*
G54D14*
X107400Y11300D03*
X98200Y10000D03*
X94042Y9842D03*
X87900Y94500D03*
X87250Y100650D03*
X98300Y67500D03*
X104500Y56200D03*
X88000Y65200D03*
X83200Y60000D03*
X48800Y87100D03*
X68800Y139000D03*
X59400Y151000D03*
X56400Y164250D03*
X67750Y160700D03*
X66100Y151000D03*
X98900Y172350D03*
X92400Y163100D03*
X80000Y158900D03*
X80400Y167200D03*
X102202Y131798D03*
X101500Y139900D03*
X100000Y175700D03*
X105500Y109500D03*
X105400Y153600D03*
X106500Y149000D03*
X105218Y137218D03*
X71500Y168500D03*
X56500Y202900D03*
X100500Y209300D03*
X75591Y202676D03*
X79843D03*
X83500Y189000D03*
X96000Y192000D03*
X72200Y202400D03*
X67500Y213500D03*
X64000D03*
X160400Y4900D03*
X111018Y11382D03*
X148300Y16700D03*
X147878Y13326D03*
X147900Y73800D03*
X153300Y22300D03*
X137400Y61900D03*
X125000Y93400D03*
X129400Y62200D03*
X169800Y39200D03*
X161400Y58700D03*
X154300Y56400D03*
X124100Y78900D03*
X137900Y49400D03*
X110781Y87200D03*
X111750Y98450D03*
X152900Y46500D03*
X114850Y95650D03*
X181700Y72700D03*
X161694Y55106D03*
X154300Y49600D03*
X111800Y113700D03*
X117600Y117700D03*
X116176Y156724D03*
X109500Y168752D03*
X180076Y179876D03*
X175600Y166800D03*
X121700Y117300D03*
X111924Y156724D03*
X109500Y164500D03*
X172000Y166800D03*
X124400Y103100D03*
X181400Y124500D03*
X172300Y192800D03*
X164200Y205100D03*
X180300Y187200D03*
X179900Y191300D03*
X180000Y198500D03*
Y183500D03*
X183683Y198517D03*
X173300Y204969D03*
X199400Y81400D03*
X236900Y85800D03*
X233700Y54400D03*
X246800Y112500D03*
X198300Y111700D03*
X188900Y173300D03*
X225100Y168100D03*
X199900Y161600D03*
X192200Y166700D03*
X195900Y162100D03*
X191600Y185600D03*
X209400Y200100D03*
X225600Y185900D03*
X230500Y191400D03*
X224100Y200100D03*
X256747Y199700D03*
X250100Y193000D03*
X267500Y182000D03*
X266000Y185100D03*
X254900Y188300D03*
X324021Y-46464D03*
X334221D03*
X344421D03*
X320021D03*
X330221D03*
X340421D03*
X329242Y-36479D03*
X339442D03*
X325242D03*
X335442D03*
X345642D03*
X329400Y50300D03*
X339100Y73300D03*
X324600Y36900D03*
X343524Y36971D03*
X346000Y34640D03*
X300800Y100100D03*
X337900Y46800D03*
X346150Y84800D03*
X313400Y119100D03*
X289600Y162100D03*
X308600Y171100D03*
X274400Y161700D03*
X327200Y178276D03*
Y174024D03*
X348200Y169900D03*
X294600Y201300D03*
X301500Y186300D03*
X332000Y192200D03*
X329400Y195900D03*
X334794Y195294D03*
X321600Y186300D03*
X323243Y183323D03*
X380500Y13200D03*
X380200Y3300D03*
X354621Y-46464D03*
X364821D03*
X375021D03*
X385221D03*
X395421D03*
X350621D03*
X360821D03*
X371021D03*
X381221D03*
X391421D03*
X349642Y-36479D03*
X359842D03*
X370042D03*
X380242D03*
X390442D03*
X400642D03*
X355842D03*
X366042D03*
X376242D03*
X386442D03*
X396642D03*
X383500Y69200D03*
X383600Y59618D03*
X383400Y46600D03*
X362400Y34500D03*
X404500Y36300D03*
X380200Y25800D03*
X349701Y64199D03*
X353100Y63900D03*
X359023Y47177D03*
X355370Y37411D03*
X355300Y81400D03*
X349700Y56000D03*
X349000Y28300D03*
X404500Y47769D03*
X409400Y69800D03*
X423500Y37800D03*
X412000Y29900D03*
X356700Y86600D03*
X353098Y55882D03*
X350300Y31800D03*
X352138Y50729D03*
X351500Y36100D03*
X355536Y50589D03*
X352700Y40000D03*
X355399Y47191D03*
X355300Y33900D03*
X391200Y35700D03*
X398805Y66200D03*
X408600Y27376D03*
X388006Y37706D03*
X395406Y66092D03*
X418650Y22850D03*
X408600Y23124D03*
X402500Y89124D03*
X375514Y85000D03*
X402500Y93376D03*
X372114Y85000D03*
X358700Y38100D03*
X362100D03*
X372400Y41100D03*
X433900Y11000D03*
X438900Y13400D03*
X428600Y16900D03*
X439000Y87700D03*
X451381Y88210D03*
Y91719D03*
X435287Y25646D03*
X441688Y74914D03*
X449400Y26433D03*
X454000Y40600D03*
X429850Y22950D03*
X461513Y48758D03*
Y52267D03*
X457245Y105151D03*
X453736D03*
X455700Y205800D03*
X524994Y-38000D03*
X530994D03*
X520500Y154500D03*
X525000Y158000D03*
X551376Y176271D03*
Y172019D03*
X517900Y103300D03*
X520970Y192569D03*
X528500Y200000D03*
G54D11*
X25700Y89200D03*
X27207Y85293D03*
X24400Y81900D03*
X22300Y85000D03*
X21800Y78600D03*
X21600Y74000D03*
X28200Y160400D03*
X84619Y-27663D03*
X89467Y-47981D03*
X84671Y-44973D03*
X79444Y-46817D03*
X90546Y-41425D03*
X90332Y-30191D03*
X85442Y-39927D03*
X79444Y-41282D03*
X90400Y-36500D03*
X85231Y-34026D03*
X79035Y-30696D03*
X79103Y-35748D03*
X107800Y4300D03*
X107000Y-49000D03*
X106800Y-53000D03*
X107100Y-36900D03*
X107500Y-33200D03*
X33200Y98700D03*
X30600Y88100D03*
X33700Y91400D03*
X29400Y92300D03*
X32800Y95000D03*
X102000Y40300D03*
X103000Y28300D03*
X105800Y40200D03*
X107000Y28300D03*
X96000Y80100D03*
X97800Y76800D03*
X93000Y73300D03*
X93800Y77000D03*
X89800Y76700D03*
X50700Y81900D03*
X58000Y81600D03*
X53000Y59800D03*
X49400Y60000D03*
X54300Y81700D03*
X71500Y39500D03*
X71700Y31500D03*
X69300Y36500D03*
X69400Y26700D03*
X86000Y36087D03*
X78600Y36200D03*
X74600Y36100D03*
X82300Y36200D03*
X32400Y160600D03*
X29200Y164000D03*
X33100Y164800D03*
X36000Y161800D03*
X31000Y156900D03*
X55600Y105100D03*
X54400Y110000D03*
X54600Y114900D03*
X59000Y107900D03*
X59700Y115200D03*
X44200Y212200D03*
X39200Y212100D03*
X44400Y217400D03*
X39300D03*
X111600Y4100D03*
X115500Y4000D03*
X119300Y3800D03*
X123000D03*
X127000Y3900D03*
X130800Y4000D03*
X111300Y-49100D03*
X111100Y-53100D03*
X111400Y-37000D03*
X111800Y-33300D03*
X131266Y85081D03*
X135025Y85092D03*
X138722Y85144D03*
X131666Y78581D03*
X135425Y78592D03*
X139122Y78644D03*
X109600Y40000D03*
X110800Y28100D03*
X138922Y94844D03*
X135225Y94792D03*
X131466Y94781D03*
X172300Y94300D03*
X169800Y91100D03*
X174900Y90900D03*
X152700Y33300D03*
X152279Y36876D03*
X153000Y40700D03*
X135100Y161900D03*
X155600Y166300D03*
X151700D03*
X134900Y165700D03*
X146165Y120044D03*
X140552Y117907D03*
X136626Y118116D03*
X158100Y116300D03*
X158000Y120900D03*
Y124800D03*
X142500Y203900D03*
X145300Y201100D03*
X148314Y203751D03*
X162100Y193800D03*
X165700Y195000D03*
X363700Y78200D03*
X421405Y90902D03*
X418437Y87727D03*
X423690Y87875D03*
X428500Y107700D03*
X424200Y103800D03*
X453500Y-9800D03*
X449900Y-9700D03*
X453400Y-13500D03*
X449800D03*
X453500Y-5700D03*
X449900D03*
X453600Y-2000D03*
X450000Y-1900D03*
X432100Y103800D03*
X495500Y219600D03*
Y210500D03*
X495400Y215300D03*
X500200Y219500D03*
X504800Y219600D03*
X504500Y210600D03*
X500200Y210400D03*
X504700Y215300D03*
X500100Y215200D03*
X540500Y219500D03*
X532200Y219300D03*
X527000Y219500D03*
X519900D03*
G54D17*
X122403Y148109D03*
X126338Y155984D03*
X130278Y148109D03*
X138148D03*
X142088Y155984D03*
X146023Y148109D03*
X149963Y155984D03*
X153898Y148109D03*
X157833Y155984D03*
X161773Y148109D03*
X177518D03*
X181458Y155984D03*
X189333D03*
X122403Y138269D03*
X126338Y130394D03*
X130278Y138269D03*
X138148D03*
X142088Y130394D03*
X149963D03*
X153898Y138269D03*
X157833Y130394D03*
X161773Y138269D03*
X173583Y130394D03*
X181458D03*
X185393Y138269D03*
X122403Y228109D03*
X126338Y235984D03*
X130278Y228109D03*
X138148D03*
X142088Y235984D03*
X146023Y228109D03*
X149963Y235984D03*
X153898Y228109D03*
X157833Y235984D03*
X161773Y228109D03*
X177518D03*
X181458Y235984D03*
X189333D03*
X122403Y218269D03*
X126338Y210394D03*
X130278Y218269D03*
X138148D03*
X142088Y210394D03*
X149963D03*
X153898Y218269D03*
X157833Y210394D03*
X161773Y218269D03*
X173583Y210394D03*
X181458D03*
X185393Y218269D03*
X193268Y148109D03*
X201143D03*
X209018D03*
X212953Y155984D03*
X224763Y148109D03*
X228703Y155984D03*
X240513Y148109D03*
X244448Y155984D03*
X252323D03*
X256258Y148109D03*
X264133D03*
X268073Y155984D03*
X193268Y138269D03*
X201143D03*
X205078Y130394D03*
X216888Y138269D03*
X220828Y130394D03*
X232638Y138269D03*
X236573Y130394D03*
X244448D03*
X248388Y138269D03*
X256258D03*
X260198Y130394D03*
X193268Y228109D03*
X201143D03*
X209018D03*
X212953Y235984D03*
X224763Y228109D03*
X228703Y235984D03*
X240513Y228109D03*
X244448Y235984D03*
X252323D03*
X256258Y228109D03*
X264133D03*
X268073Y235984D03*
X193268Y218269D03*
X201143D03*
X205078Y210394D03*
X216888Y218269D03*
X220828Y210394D03*
X232638Y218269D03*
X236573Y210394D03*
X244448D03*
X248388Y218269D03*
X256258D03*
X260198Y210394D03*
X279883Y148109D03*
X283818Y155984D03*
X295628Y148109D03*
X299568Y155984D03*
X311378Y148109D03*
X315313Y155984D03*
X323188D03*
X331063D03*
X334998Y148109D03*
X346813Y155984D03*
X272008Y138269D03*
X275943Y130394D03*
X287758Y138269D03*
X291693Y130394D03*
X303503Y138269D03*
X307443Y130394D03*
X315313D03*
X323188D03*
X327128Y138269D03*
X338938Y130394D03*
X342873Y138269D03*
X279883Y228109D03*
X283818Y235984D03*
X295628Y228109D03*
X299568Y235984D03*
X311378Y228109D03*
X315313Y235984D03*
X323188D03*
X331063D03*
X334998Y228109D03*
X346813Y235984D03*
X272008Y218269D03*
X275943Y210394D03*
X287758Y218269D03*
X291693Y210394D03*
X303503Y218269D03*
X307443Y210394D03*
X315313D03*
X323188D03*
X327128Y218269D03*
X338938Y210394D03*
X342873Y218269D03*
X350748Y148109D03*
X362558Y155984D03*
X366498Y148109D03*
X378308Y155984D03*
X382243Y148109D03*
X394053Y155984D03*
X397993Y148109D03*
X409803Y155984D03*
X413738Y148109D03*
X425553Y155984D03*
X429488Y148109D03*
X354683Y130394D03*
X358623Y138269D03*
X370433Y130394D03*
X374368Y138269D03*
X386183Y130394D03*
X390118Y138269D03*
X401928Y130394D03*
X405868Y138269D03*
X417678Y130394D03*
X421613Y138269D03*
X350748Y228109D03*
X362558Y235984D03*
X366498Y228109D03*
X378308Y235984D03*
X382243Y228109D03*
X394053Y235984D03*
X397993Y228109D03*
X409803Y235984D03*
X413738Y228109D03*
X425553Y235984D03*
X429488Y228109D03*
X354683Y210394D03*
X358623Y218269D03*
X370433Y210394D03*
X374368Y218269D03*
X386183Y210394D03*
X390118Y218269D03*
X401928Y210394D03*
X405868Y218269D03*
X417678Y210394D03*
X421613Y218269D03*
X441298Y155984D03*
X445238Y148109D03*
X433423Y130394D03*
X437363Y138269D03*
X445238D03*
X449173Y130394D03*
X441298Y235984D03*
X445238Y228109D03*
X433423Y210394D03*
X437363Y218269D03*
X445238D03*
X449173Y210394D03*
G54D15*
X83400Y55300D03*
X87300D03*
X75500Y55400D03*
X79099Y55280D03*
G54D13*
X6487Y175762D03*
Y165762D03*
X14947Y175971D03*
Y165971D03*
X22700Y190800D03*
X26300D03*
X26600Y201000D03*
X23000D03*
X6487Y235762D03*
X25453Y235870D03*
X15453D03*
X6487Y225762D03*
Y215762D03*
Y205762D03*
Y195762D03*
Y185762D03*
X14947Y195971D03*
Y185971D03*
X92940Y6625D03*
X99000Y13800D03*
X95906Y-53300D03*
X99200Y18100D03*
X76300Y79700D03*
X78900Y82400D03*
X78200Y76200D03*
X78300Y72600D03*
X78400Y68900D03*
X74700Y73100D03*
X73500Y76600D03*
X74900Y65800D03*
X74800Y69500D03*
X71000Y73500D03*
X67400Y76200D03*
X71100Y69800D03*
X67200Y72400D03*
Y68800D03*
X72400Y22300D03*
X90100Y23100D03*
X64200Y99200D03*
X78000Y99900D03*
X93900Y95300D03*
X104600Y95000D03*
X102400Y92600D03*
X106800Y92700D03*
X104600Y90500D03*
X45800Y54800D03*
X45200Y89400D03*
X30700Y56400D03*
X98300Y72000D03*
X39900Y72800D03*
X64600Y104500D03*
X78000Y105800D03*
X62000Y142900D03*
X56300Y180000D03*
X101500Y135908D03*
X62700Y150100D03*
X69000Y143300D03*
X79000Y142500D03*
X77000Y140300D03*
X81300Y140400D03*
X79200Y138100D03*
X104743Y174953D03*
X98900Y126800D03*
X85700Y129900D03*
X85900Y126300D03*
X81700Y129700D03*
X81800Y125900D03*
X100800Y189700D03*
X100700Y182900D03*
X98400Y233100D03*
X59600Y214000D03*
X100700Y186300D03*
X35453Y235870D03*
X45453D03*
X55453D03*
X65453D03*
X75453D03*
X84400Y232900D03*
X89600D03*
X94900Y233000D03*
X161100Y13600D03*
X126800Y-53409D03*
X135182D03*
X144631D03*
X154080D03*
X163529D03*
X172977D03*
X116900Y-35400D03*
X121801Y16999D03*
X146600Y3400D03*
X159450Y8750D03*
X182000Y66700D03*
X174400Y32500D03*
X176300Y45200D03*
X159450Y97400D03*
X151150Y83500D03*
X124900Y88900D03*
X161800Y71100D03*
X117200Y65750D03*
X116900Y59450D03*
X134000Y63400D03*
X151550Y87500D03*
X132600Y39900D03*
X167100Y181200D03*
X156600Y109800D03*
X152650D03*
X148950Y109600D03*
X116100Y169700D03*
X120400Y169800D03*
X125300Y170200D03*
X163300Y178900D03*
X240100Y20900D03*
X221900Y5100D03*
X235600Y5300D03*
X247200Y5400D03*
X195200Y5700D03*
X191875Y-53409D03*
X201324D03*
X210773D03*
X220221D03*
X229670D03*
X239119D03*
X248568D03*
X258017D03*
X267466D03*
X252300Y22200D03*
X255900Y35000D03*
X246500Y47900D03*
X200500Y31500D03*
X216300Y46700D03*
X226600Y21400D03*
X198300Y73200D03*
X196400Y91600D03*
X193900Y51600D03*
X202800Y50200D03*
X218900Y65600D03*
X198900Y21200D03*
X230300Y45100D03*
X233800Y66000D03*
X262400Y169900D03*
X202300Y165100D03*
X196850Y177950D03*
X242800Y200600D03*
X243000Y185300D03*
X239400Y191500D03*
X345042Y-41479D03*
X339942D03*
X324642D03*
X334842D03*
X329742D03*
X319070Y-41541D03*
X276914Y-53409D03*
X286363D03*
X295812D03*
X305261D03*
X314710D03*
X324158D03*
X333607D03*
X343056D03*
X328000Y30500D03*
Y59000D03*
X339649Y41539D03*
X328655Y170950D03*
X326600Y182000D03*
X295800Y195900D03*
X396042Y-41479D03*
X390942D03*
X380742D03*
X385842D03*
X375642D03*
X370542D03*
X365442D03*
X360342D03*
X355242D03*
X401142D03*
X350142D03*
X423852Y4375D03*
X420252Y-36925D03*
X410052Y-36825D03*
X380500Y17100D03*
X352505Y-53409D03*
X361954D03*
X371403D03*
X380851D03*
X390300D03*
X399815Y-52741D03*
X415100Y3400D03*
X352600Y7600D03*
X380200Y6800D03*
X405500Y29200D03*
X370400Y88200D03*
X377800Y87800D03*
X383300Y50700D03*
X383500Y65800D03*
X388000Y41600D03*
X394500Y34000D03*
X380300Y21600D03*
X405800Y21100D03*
Y94200D03*
X405600Y87500D03*
X420322Y56072D03*
X423202Y56119D03*
X426128Y50188D03*
Y53348D03*
X426065Y56213D03*
X426113Y59046D03*
X425971Y62050D03*
X423500Y34200D03*
X416300Y37100D03*
X418705Y34695D03*
X405569Y72731D03*
X409026Y61211D03*
X401211Y46589D03*
X373300Y35400D03*
X384000Y41600D03*
X391600Y29400D03*
X361600Y69100D03*
X436752Y4175D03*
X498052Y-625D03*
X490200Y-6400D03*
X488652Y-18225D03*
X496352Y-19025D03*
X432452Y-36225D03*
X447252Y-47725D03*
X445252Y-37225D03*
X455701Y-53425D03*
X502945D03*
X493496D03*
X484047D03*
X474598D03*
X465149D03*
X446252D03*
X469300Y87600D03*
X459652Y31575D03*
X458100Y47300D03*
Y53700D03*
X448200Y93000D03*
X448369Y86631D03*
X432091Y56151D03*
X429056Y56135D03*
X457400Y41800D03*
X468588Y55981D03*
X431382Y35283D03*
X437300Y91100D03*
X454085Y63272D03*
X460535Y76560D03*
X456662Y76376D03*
X452496Y70099D03*
X454500Y29300D03*
X439418Y26110D03*
X452888Y108444D03*
X457097Y108548D03*
X466361Y230936D03*
X467506Y226106D03*
X502000Y229400D03*
X466010Y216328D03*
X492961Y227336D03*
X480761Y227936D03*
X505961Y236936D03*
X488161Y236336D03*
X479761D03*
X499761D03*
X532137Y7890D03*
X532691Y-17725D03*
X531600Y-31800D03*
X523300Y-32100D03*
X531291Y-53425D03*
X521842D03*
X512393D03*
X534737Y40290D03*
X534337Y52790D03*
X534637Y74290D03*
Y92590D03*
X532778Y21738D03*
X512000Y158400D03*
X511900Y174400D03*
Y142700D03*
X521900Y179500D03*
X548200Y169900D03*
X548300Y178100D03*
X578337Y166890D03*
X577748Y181113D03*
X529000Y158500D03*
X521600Y158400D03*
X524200Y181600D03*
X519700Y181900D03*
X521900Y184000D03*
X545300Y236800D03*
X529500Y236400D03*
X519761Y236336D03*
X537200Y236400D03*
X559761Y236336D03*
X579761D03*
X577748Y211113D03*
X578337Y226890D03*
X577748Y191113D03*
Y201113D03*
X524000Y200000D03*
X593337Y166890D03*
Y176890D03*
X608337Y166890D03*
Y176890D03*
X599761Y236336D03*
X593337Y206890D03*
Y216890D03*
Y226890D03*
Y186890D03*
Y196890D03*
X608337Y206890D03*
Y216890D03*
Y226890D03*
Y186890D03*
Y196890D03*
G54D20*
X539370Y190256D03*
Y206792D03*
X561024D03*
G54D16*
X168268Y143189D03*
Y223189D03*
X456258Y143189D03*
Y223189D03*
G54D10*
X21800Y-41500D03*
X14794Y226306D03*
X542107Y17432D03*
X585785Y228866D03*
X610300Y-43600D03*
X612500Y540800D03*
G54D21*
X561024Y190256D03*
G54D19*
X383600Y55532D03*
X528590Y-12237D03*
Y2763D03*
G54D18*
X134213Y155984D03*
X173583D03*
X185393Y148109D03*
X134213Y130394D03*
X146023Y138269D03*
X177518D03*
X189333Y130394D03*
X134213Y235984D03*
X173583D03*
X185393Y228109D03*
X134213Y210394D03*
X146023Y218269D03*
X177518D03*
X189333Y210394D03*
X197203Y155984D03*
X205078D03*
X216888Y148109D03*
X220828Y155984D03*
X232638Y148109D03*
X236573Y155984D03*
X248388Y148109D03*
X260198Y155984D03*
X197203Y130394D03*
X209018Y138269D03*
X212953Y130394D03*
X224763Y138269D03*
X228703Y130394D03*
X240513Y138269D03*
X252323Y130394D03*
X264133Y138269D03*
X268073Y130394D03*
X197203Y235984D03*
X205078D03*
X216888Y228109D03*
X220828Y235984D03*
X232638Y228109D03*
X236573Y235984D03*
X248388Y228109D03*
X260198Y235984D03*
X197203Y210394D03*
X209018Y218269D03*
X212953Y210394D03*
X224763Y218269D03*
X228703Y210394D03*
X240513Y218269D03*
X252323Y210394D03*
X264133Y218269D03*
X268073Y210394D03*
X272008Y148109D03*
X275943Y155984D03*
X287758Y148109D03*
X291693Y155984D03*
X303503Y148109D03*
X307443Y155984D03*
X319253Y148109D03*
X327128D03*
X338938Y155984D03*
X342873Y148109D03*
X279883Y138269D03*
X283818Y130394D03*
X295628Y138269D03*
X299568Y130394D03*
X311378Y138269D03*
X319253D03*
X331063Y130394D03*
X334998Y138269D03*
X346813Y130394D03*
X272008Y228109D03*
X275943Y235984D03*
X287758Y228109D03*
X291693Y235984D03*
X303503Y228109D03*
X307443Y235984D03*
X319253Y228109D03*
X327128D03*
X338938Y235984D03*
X342873Y228109D03*
X279883Y218269D03*
X283818Y210394D03*
X295628Y218269D03*
X299568Y210394D03*
X311378Y218269D03*
X319253D03*
X331063Y210394D03*
X334998Y218269D03*
X346813Y210394D03*
X354683Y155984D03*
X358623Y148109D03*
X370433Y155984D03*
X374368Y148109D03*
X386183Y155984D03*
X390118Y148109D03*
X401928Y155984D03*
X405868Y148109D03*
X417678Y155984D03*
X421613Y148109D03*
X350748Y138269D03*
X362558Y130394D03*
X366498Y138269D03*
X378308Y130394D03*
X382243Y138269D03*
X394053Y130394D03*
X397993Y138269D03*
X409803Y130394D03*
X413738Y138269D03*
X425553Y130394D03*
X429488Y138269D03*
X354683Y235984D03*
X358623Y228109D03*
X370433Y235984D03*
X374368Y228109D03*
X386183Y235984D03*
X390118Y228109D03*
X401928Y235984D03*
X405868Y228109D03*
X417678Y235984D03*
X421613Y228109D03*
X350748Y218269D03*
X362558Y210394D03*
X366498Y218269D03*
X378308Y210394D03*
X382243Y218269D03*
X394053Y210394D03*
X397993Y218269D03*
X409803Y210394D03*
X413738Y218269D03*
X425553Y210394D03*
X429488Y218269D03*
X433423Y155984D03*
X437363Y148109D03*
X449173Y155984D03*
X441298Y130394D03*
X433423Y235984D03*
X437363Y228109D03*
X449173Y235984D03*
X441298Y210394D03*
%LPC*%
G75*
G54D22*
G01X-84798Y-164972D02*
Y-244972D01*
G01D02*
X1172402D01*
G01X-88798Y-148972D02*
G02I-12000J0D01*
G01X-93948D02*
G02I-6850J0D01*
G01X-100798Y-164972D02*
Y-132972D01*
G01X-84798Y-148972D02*
X-116798D01*
G01X-84798Y-164972D02*
X1172402D01*
G01X-84798Y-200472D02*
X1172402D01*
G01X384902Y-164972D02*
Y-244972D01*
G01X522402Y-164972D02*
Y-244972D01*
G01X637402Y-164972D02*
Y-244972D01*
G01X804902Y-164972D02*
Y-244972D01*
G01X974902Y-164972D02*
Y-244972D01*
G01X1172402Y-164972D02*
Y-244972D01*
G01X1200402Y-148972D02*
G02I-12000J0D01*
G01X1195252D02*
G02I-6850J0D01*
G01X1188402Y-164972D02*
Y-132972D01*
G01X1204402Y-148972D02*
X1172402D01*
G54D23*
G01X-65001Y-234972D02*
Y-217472D01*
X-60635D01*
X-58888Y-218347D01*
X-57578Y-219514D01*
X-56486Y-221263D01*
X-55613Y-223306D01*
X-55395Y-226222D01*
X-55613Y-229139D01*
X-56486Y-231181D01*
X-57578Y-232931D01*
X-58888Y-234097D01*
X-60635Y-234972D01*
X-65001D01*
G01X-48157Y-217472D02*
X-42698Y-234972D01*
X-37239Y-217472D01*
G01X-25198D02*
Y-234972D01*
G01X-30220Y-217472D02*
X-20176D01*
G01X5435Y-234972D02*
Y-217472D01*
X10894D01*
X12640Y-218347D01*
X13732Y-219514D01*
X14169Y-221847D01*
X13732Y-224181D01*
X12422Y-225639D01*
X10894Y-226514D01*
X5435D01*
G01X10894D02*
X14169Y-234972D01*
G01X27302Y-223306D02*
Y-234972D01*
G01Y-218639D02*
X26865Y-218347D01*
Y-217764D01*
X27302Y-217472D01*
X27739Y-217764D01*
Y-218347D01*
X27302Y-218639D01*
G01X41527Y-232931D02*
X42619Y-234097D01*
X44147Y-234972D01*
X45457D01*
X46767Y-234389D01*
X47640Y-233514D01*
X48077Y-232348D01*
X47859Y-230597D01*
X46985Y-229722D01*
X43055Y-227972D01*
X42182Y-225930D01*
X42619Y-224472D01*
X43492Y-223597D01*
X44802Y-223306D01*
X46112Y-223597D01*
X47422Y-224472D01*
G01X59027Y-227097D02*
X66014D01*
X65359Y-225055D01*
X64267Y-223889D01*
X62739Y-223306D01*
X61210Y-223597D01*
X59900Y-224472D01*
X59027Y-226514D01*
X58590Y-228264D01*
Y-230014D01*
X59027Y-231764D01*
X60119Y-233514D01*
X61429Y-234680D01*
X62957Y-234972D01*
X64485Y-234389D01*
X66014Y-232639D01*
G01X76745Y-234972D02*
Y-223306D01*
G01Y-225639D02*
X77837Y-224472D01*
X78929Y-223597D01*
X80457Y-223306D01*
X81548Y-223597D01*
X82859Y-224472D01*
G01X119605Y-218931D02*
X118295Y-218055D01*
X116767Y-217472D01*
X115020D01*
X113055Y-218347D01*
X111527Y-219805D01*
X110435Y-221556D01*
X109562Y-224472D01*
X109343Y-227097D01*
X109780Y-229722D01*
X110435Y-231472D01*
X111745Y-233222D01*
X113274Y-234389D01*
X114802Y-234972D01*
X116330D01*
X117859Y-234389D01*
X119169Y-233514D01*
X120261Y-232348D01*
G01X136232Y-234972D02*
Y-223306D01*
G01Y-225347D02*
X135359Y-224181D01*
X134048Y-223597D01*
X132520Y-223306D01*
X130992Y-223889D01*
X129682Y-225055D01*
X128808Y-226805D01*
X128372Y-229139D01*
X128808Y-231472D01*
X129682Y-233222D01*
X130992Y-234389D01*
X132520Y-234972D01*
X134048Y-234680D01*
X135359Y-233806D01*
X136232Y-232639D01*
G01X146745Y-234972D02*
Y-223306D01*
G01Y-225639D02*
X147837Y-224472D01*
X148929Y-223597D01*
X150457Y-223306D01*
X151548Y-223597D01*
X152859Y-224472D01*
G01X171232Y-217472D02*
Y-234972D01*
G01Y-232348D02*
X170359Y-233806D01*
X169048Y-234680D01*
X167520Y-234972D01*
X165774Y-234389D01*
X164464Y-232931D01*
X163590Y-231181D01*
X163372Y-229139D01*
X163590Y-227097D01*
X164464Y-225347D01*
X165774Y-223889D01*
X167520Y-223306D01*
X169048Y-223597D01*
X170140Y-224181D01*
X171232Y-225347D01*
G01X178252Y-240805D02*
X191352D01*
G01X197717Y-232639D02*
X199464Y-234097D01*
X201429Y-234972D01*
X203175D01*
X204922Y-234097D01*
X206232Y-232639D01*
X206887Y-230597D01*
X206450Y-228556D01*
X205359Y-226805D01*
X203394Y-225639D01*
X200774Y-225055D01*
X199245Y-223889D01*
X198590Y-221847D01*
X199027Y-219805D01*
X200119Y-218347D01*
X201647Y-217472D01*
X203175D01*
X204704Y-218055D01*
X206014Y-219514D01*
G01X215217Y-232639D02*
X216964Y-234097D01*
X218929Y-234972D01*
X220675D01*
X222422Y-234097D01*
X223732Y-232639D01*
X224387Y-230597D01*
X223950Y-228556D01*
X222859Y-226805D01*
X220894Y-225639D01*
X218274Y-225055D01*
X216745Y-223889D01*
X216090Y-221847D01*
X216527Y-219805D01*
X217619Y-218347D01*
X219147Y-217472D01*
X220675D01*
X222204Y-218055D01*
X223514Y-219514D01*
G01X250654Y-220389D02*
X251964Y-218639D01*
X253492Y-217764D01*
X255239Y-217472D01*
X257422Y-218055D01*
X258950Y-219514D01*
X259387Y-221263D01*
X259169Y-223014D01*
X258295Y-224472D01*
X253929Y-227389D01*
X251964Y-229430D01*
X250654Y-232348D01*
X250217Y-234972D01*
X259387D01*
G01X286527Y-232931D02*
X287619Y-234097D01*
X289147Y-234972D01*
X290457D01*
X291767Y-234389D01*
X292640Y-233514D01*
X293077Y-232348D01*
X292859Y-230597D01*
X291985Y-229722D01*
X288055Y-227972D01*
X287182Y-225930D01*
X287619Y-224472D01*
X288492Y-223597D01*
X289802Y-223306D01*
X291112Y-223597D01*
X292422Y-224472D01*
G01X307302Y-234972D02*
Y-217472D01*
G01X324802Y-234972D02*
X323492Y-234680D01*
X322182Y-233514D01*
X321308Y-231472D01*
X320872Y-229139D01*
X321308Y-226805D01*
X322182Y-224764D01*
X323492Y-223597D01*
X324802Y-223306D01*
X326112Y-223597D01*
X327422Y-224764D01*
X328295Y-226805D01*
X328514Y-229139D01*
X328295Y-231472D01*
X327422Y-233514D01*
X326112Y-234680D01*
X324802Y-234972D01*
G01X342302Y-217472D02*
Y-234972D01*
G01X339245Y-223306D02*
X345359D01*
G01X356527Y-232931D02*
X357619Y-234097D01*
X359147Y-234972D01*
X360457D01*
X361767Y-234389D01*
X362640Y-233514D01*
X363077Y-232348D01*
X362859Y-230597D01*
X361985Y-229722D01*
X358055Y-227972D01*
X357182Y-225930D01*
X357619Y-224472D01*
X358492Y-223597D01*
X359802Y-223306D01*
X361112Y-223597D01*
X362422Y-224472D01*
G01X109125Y-189972D02*
Y-172472D01*
X114802Y-187055D01*
X120479Y-172472D01*
Y-189972D01*
G01X132302D02*
X130992Y-189680D01*
X129682Y-188514D01*
X128808Y-186472D01*
X128372Y-184139D01*
X128808Y-181805D01*
X129682Y-179764D01*
X130992Y-178597D01*
X132302Y-178306D01*
X133612Y-178597D01*
X134922Y-179764D01*
X135795Y-181805D01*
X136014Y-184139D01*
X135795Y-186472D01*
X134922Y-188514D01*
X133612Y-189680D01*
X132302Y-189972D01*
G01X153732Y-172472D02*
Y-189972D01*
G01Y-187348D02*
X152859Y-188806D01*
X151548Y-189680D01*
X150020Y-189972D01*
X148274Y-189389D01*
X146964Y-187931D01*
X146090Y-186181D01*
X145872Y-184139D01*
X146090Y-182097D01*
X146964Y-180347D01*
X148274Y-178889D01*
X150020Y-178306D01*
X151548Y-178597D01*
X152640Y-179181D01*
X153732Y-180347D01*
G01X164027Y-182097D02*
X171014D01*
X170359Y-180055D01*
X169267Y-178889D01*
X167739Y-178306D01*
X166210Y-178597D01*
X164900Y-179472D01*
X164027Y-181514D01*
X163590Y-183264D01*
Y-185014D01*
X164027Y-186764D01*
X165119Y-188514D01*
X166429Y-189680D01*
X167957Y-189972D01*
X169485Y-189389D01*
X171014Y-187639D01*
G01X184802Y-189972D02*
Y-172472D01*
G01X418602Y-234972D02*
Y-217472D01*
X415982Y-220972D01*
G01Y-234972D02*
X421222D01*
G01X431299Y-232348D02*
X432608Y-233806D01*
X434137Y-234680D01*
X436102Y-234972D01*
X438067Y-234389D01*
X439595Y-233222D01*
X440687Y-231181D01*
X440905Y-228847D01*
X440469Y-226514D01*
X439377Y-225055D01*
X437848Y-223889D01*
X436320Y-223597D01*
X434792Y-223889D01*
X432827Y-225055D01*
X433482Y-217472D01*
X439377D01*
G01X449890Y-232931D02*
X451419Y-234389D01*
X453165Y-234972D01*
X454912Y-234389D01*
X456440Y-232639D01*
X457532Y-230014D01*
X457969Y-227389D01*
Y-224181D01*
X457532Y-221556D01*
X456440Y-219222D01*
X455130Y-218055D01*
X453602Y-217472D01*
X451855Y-218055D01*
X450545Y-219222D01*
X449672Y-220972D01*
X449235Y-223306D01*
X449672Y-225347D01*
X450764Y-227389D01*
X452074Y-228556D01*
X453602Y-228847D01*
X455348Y-228264D01*
X456659Y-226805D01*
X457969Y-224181D01*
G01X466954Y-227681D02*
X468482Y-225639D01*
X469792Y-224472D01*
X471539Y-223889D01*
X473067Y-224472D01*
X474159Y-225639D01*
X475032Y-227389D01*
X475250Y-229430D01*
X475032Y-231181D01*
X474159Y-232931D01*
X472848Y-234389D01*
X471320Y-234972D01*
X469574Y-234389D01*
X468045Y-232639D01*
X467172Y-230014D01*
X466954Y-227097D01*
X467390Y-223306D01*
X468045Y-221263D01*
X469137Y-219222D01*
X470665Y-217764D01*
X472194Y-217472D01*
X473722Y-218055D01*
X474814Y-219514D01*
G01X488602Y-234972D02*
X490130Y-234680D01*
X491877Y-233806D01*
X492969Y-232348D01*
X493405Y-230305D01*
X492969Y-228264D01*
X491659Y-226514D01*
X489694Y-225639D01*
X487510D01*
X486200Y-225055D01*
X485108Y-223597D01*
X484672Y-221556D01*
X485327Y-219514D01*
X486855Y-218055D01*
X488602Y-217472D01*
X490348Y-218055D01*
X491877Y-219514D01*
X492532Y-221556D01*
X492095Y-223597D01*
X491004Y-225055D01*
X489694Y-225639D01*
X487510D01*
X485545Y-226514D01*
X484235Y-228264D01*
X483799Y-230305D01*
X484235Y-232348D01*
X485327Y-233806D01*
X487074Y-234680D01*
X488602Y-234972D01*
G01X405485Y-189972D02*
Y-172472D01*
X410725D01*
X412472Y-173347D01*
X413782Y-175389D01*
X414219Y-177722D01*
X413782Y-180055D01*
X412690Y-181805D01*
X410725Y-182681D01*
X405485D01*
G01X432155Y-173931D02*
X430845Y-173055D01*
X429317Y-172472D01*
X427570D01*
X425605Y-173347D01*
X424077Y-174805D01*
X422985Y-176556D01*
X422112Y-179472D01*
X421893Y-182097D01*
X422330Y-184722D01*
X422985Y-186472D01*
X424295Y-188222D01*
X425824Y-189389D01*
X427352Y-189972D01*
X428880D01*
X430409Y-189389D01*
X431719Y-188514D01*
X432811Y-187348D01*
G01X446598Y-180639D02*
X447472Y-179764D01*
X448127Y-178306D01*
X448564Y-176263D01*
X448127Y-174514D01*
X447254Y-173347D01*
X445725Y-172472D01*
X439830D01*
Y-189972D01*
X447035D01*
X448564Y-188806D01*
X449437Y-187055D01*
X449874Y-185014D01*
X449437Y-182972D01*
X448127Y-181222D01*
X446598Y-180639D01*
X439830D01*
G01X455802Y-195805D02*
X468902D01*
G01X474830Y-189972D02*
Y-172472D01*
X484874Y-189972D01*
Y-172472D01*
G01X497352Y-189972D02*
X495605Y-189680D01*
X494077Y-188514D01*
X492767Y-186764D01*
X491893Y-184722D01*
X491457Y-182389D01*
Y-180055D01*
X491893Y-177722D01*
X492767Y-175680D01*
X494077Y-173931D01*
X495605Y-172764D01*
X497352Y-172472D01*
X499098Y-172764D01*
X500627Y-173931D01*
X501937Y-175680D01*
X502811Y-177722D01*
X503247Y-180055D01*
Y-182389D01*
X502811Y-184722D01*
X501937Y-186764D01*
X500627Y-188514D01*
X499098Y-189680D01*
X497352Y-189972D01*
G01X571152Y-234972D02*
Y-217472D01*
X568532Y-220972D01*
G01Y-234972D02*
X573772D01*
G01X583193D02*
X588652Y-217472D01*
X594111Y-234972D01*
G01X592145Y-228847D02*
X585158D01*
G01X548193Y-172472D02*
X553652Y-189972D01*
X559111Y-172472D01*
G01X575519Y-189972D02*
X566785D01*
Y-172472D01*
X575519D01*
G01X572025Y-180930D02*
X566785D01*
G01X584285Y-189972D02*
Y-172472D01*
X589744D01*
X591490Y-173347D01*
X592582Y-174514D01*
X593019Y-176847D01*
X592582Y-179181D01*
X591272Y-180639D01*
X589744Y-181514D01*
X584285D01*
G01X589744D02*
X593019Y-189972D01*
G01X606152Y-190555D02*
X605715Y-190264D01*
Y-189680D01*
X606152Y-189389D01*
X606589Y-189680D01*
Y-190264D01*
X606152Y-190555D01*
G01X681735Y-217472D02*
Y-234972D01*
X690469D01*
G01X699454Y-220389D02*
X700764Y-218639D01*
X702292Y-217764D01*
X704039Y-217472D01*
X706222Y-218055D01*
X707750Y-219514D01*
X708187Y-221263D01*
X707969Y-223014D01*
X707095Y-224472D01*
X702729Y-227389D01*
X700764Y-229430D01*
X699454Y-232348D01*
X699017Y-234972D01*
X708187D01*
G01X722412Y-226222D02*
X726779D01*
Y-231472D01*
X725469Y-233222D01*
X723940Y-234389D01*
X721757Y-234972D01*
X719574Y-234389D01*
X718045Y-233222D01*
X716735Y-231472D01*
X715862Y-229430D01*
X715425Y-227097D01*
Y-225055D01*
X715862Y-223306D01*
X716735Y-221263D01*
X718045Y-219514D01*
X719355Y-218347D01*
X721102Y-217472D01*
X722630D01*
X724377Y-218055D01*
X725687Y-219222D01*
G01X733580Y-234972D02*
Y-217472D01*
X743624Y-234972D01*
Y-217472D01*
G01X751299Y-234972D02*
Y-217472D01*
X755665D01*
X757412Y-218347D01*
X758722Y-219514D01*
X759814Y-221263D01*
X760687Y-223306D01*
X760905Y-226222D01*
X760687Y-229139D01*
X759814Y-231181D01*
X758722Y-232931D01*
X757412Y-234097D01*
X755665Y-234972D01*
X751299D01*
G01X681735Y-172472D02*
Y-189972D01*
X690469D01*
G01X707532D02*
Y-178306D01*
G01Y-180347D02*
X706659Y-179181D01*
X705348Y-178597D01*
X703820Y-178306D01*
X702292Y-178889D01*
X700982Y-180055D01*
X700108Y-181805D01*
X699672Y-184139D01*
X700108Y-186472D01*
X700982Y-188222D01*
X702292Y-189389D01*
X703820Y-189972D01*
X705348Y-189680D01*
X706659Y-188806D01*
X707532Y-187639D01*
G01X716517Y-195222D02*
X717827Y-195805D01*
X719574Y-195222D01*
X720665Y-194056D01*
X721539Y-192597D01*
X722848Y-187931D01*
X725687Y-178306D01*
G01X718700D02*
X722848Y-187931D01*
G01X735327Y-182097D02*
X742314D01*
X741659Y-180055D01*
X740567Y-178889D01*
X739039Y-178306D01*
X737510Y-178597D01*
X736200Y-179472D01*
X735327Y-181514D01*
X734890Y-183264D01*
Y-185014D01*
X735327Y-186764D01*
X736419Y-188514D01*
X737729Y-189680D01*
X739257Y-189972D01*
X740785Y-189389D01*
X742314Y-187639D01*
G01X753045Y-189972D02*
Y-178306D01*
G01Y-180639D02*
X754137Y-179472D01*
X755229Y-178597D01*
X756757Y-178306D01*
X757848Y-178597D01*
X759159Y-179472D01*
G01X824705Y-218931D02*
X823395Y-218055D01*
X821867Y-217472D01*
X820120D01*
X818155Y-218347D01*
X816627Y-219805D01*
X815535Y-221556D01*
X814662Y-224472D01*
X814443Y-227097D01*
X814880Y-229722D01*
X815535Y-231472D01*
X816845Y-233222D01*
X818374Y-234389D01*
X819902Y-234972D01*
X821430D01*
X822959Y-234389D01*
X824269Y-233514D01*
X825361Y-232348D01*
G01X837402Y-234972D02*
X835655Y-234680D01*
X834127Y-233514D01*
X832817Y-231764D01*
X831943Y-229722D01*
X831507Y-227389D01*
Y-225055D01*
X831943Y-222722D01*
X832817Y-220680D01*
X834127Y-218931D01*
X835655Y-217764D01*
X837402Y-217472D01*
X839148Y-217764D01*
X840677Y-218931D01*
X841987Y-220680D01*
X842861Y-222722D01*
X843297Y-225055D01*
Y-227389D01*
X842861Y-229722D01*
X841987Y-231764D01*
X840677Y-233514D01*
X839148Y-234680D01*
X837402Y-234972D01*
G01X849880D02*
Y-217472D01*
X859924Y-234972D01*
Y-217472D01*
G01X867380Y-234972D02*
Y-217472D01*
X877424Y-234972D01*
Y-217472D01*
G01X887282D02*
X892522D01*
G01X889902D02*
Y-234972D01*
G01X887282D02*
X892522D01*
G01X911769D02*
X903035D01*
Y-217472D01*
X911769D01*
G01X908275Y-225930D02*
X903035D01*
G01X937817Y-234972D02*
X946987Y-217472D01*
G01X937817D02*
X946987Y-234972D01*
G01X955317D02*
Y-217472D01*
G01X964487D02*
Y-234972D01*
G01Y-226222D02*
X955317D01*
G01X823849Y-189972D02*
Y-172472D01*
X828215D01*
X829962Y-173347D01*
X831272Y-174514D01*
X832364Y-176263D01*
X833237Y-178306D01*
X833455Y-181222D01*
X833237Y-184139D01*
X832364Y-186181D01*
X831272Y-187931D01*
X829962Y-189097D01*
X828215Y-189972D01*
X823849D01*
G01X842877Y-182097D02*
X849864D01*
X849209Y-180055D01*
X848117Y-178889D01*
X846589Y-178306D01*
X845060Y-178597D01*
X843750Y-179472D01*
X842877Y-181514D01*
X842440Y-183264D01*
Y-185014D01*
X842877Y-186764D01*
X843969Y-188514D01*
X845279Y-189680D01*
X846807Y-189972D01*
X848335Y-189389D01*
X849864Y-187639D01*
G01X860377Y-187931D02*
X861469Y-189097D01*
X862997Y-189972D01*
X864307D01*
X865617Y-189389D01*
X866490Y-188514D01*
X866927Y-187348D01*
X866709Y-185597D01*
X865835Y-184722D01*
X861905Y-182972D01*
X861032Y-180930D01*
X861469Y-179472D01*
X862342Y-178597D01*
X863652Y-178306D01*
X864962Y-178597D01*
X866272Y-179472D01*
G01X881152Y-178306D02*
Y-189972D01*
G01Y-173639D02*
X880715Y-173347D01*
Y-172764D01*
X881152Y-172472D01*
X881589Y-172764D01*
Y-173347D01*
X881152Y-173639D01*
G01X895595Y-194347D02*
X897124Y-195514D01*
X898870Y-195805D01*
X900398Y-195514D01*
X901709Y-194056D01*
X902582Y-192014D01*
Y-178306D01*
G01Y-180639D02*
X901709Y-179472D01*
X900398Y-178597D01*
X898870Y-178306D01*
X897124Y-178889D01*
X896032Y-180055D01*
X895158Y-182097D01*
X894722Y-184139D01*
X894940Y-185889D01*
X895814Y-187931D01*
X897124Y-189389D01*
X898870Y-189972D01*
X900180Y-189680D01*
X901709Y-188514D01*
X902582Y-187348D01*
G01X912440Y-189972D02*
Y-178306D01*
G01Y-181222D02*
X913314Y-179764D01*
X914624Y-178597D01*
X916370Y-178306D01*
X917898Y-178597D01*
X919209Y-179764D01*
X919864Y-181805D01*
Y-189972D01*
G01X930377Y-182097D02*
X937364D01*
X936709Y-180055D01*
X935617Y-178889D01*
X934089Y-178306D01*
X932560Y-178597D01*
X931250Y-179472D01*
X930377Y-181514D01*
X929940Y-183264D01*
Y-185014D01*
X930377Y-186764D01*
X931469Y-188514D01*
X932779Y-189680D01*
X934307Y-189972D01*
X935835Y-189389D01*
X937364Y-187639D01*
G01X948095Y-189972D02*
Y-178306D01*
G01Y-180639D02*
X949187Y-179472D01*
X950279Y-178597D01*
X951807Y-178306D01*
X952898Y-178597D01*
X954209Y-179472D01*
G01X994852Y-217472D02*
X993105Y-218055D01*
X991795Y-219514D01*
X990922Y-221263D01*
X990267Y-223597D01*
X990049Y-226222D01*
X990267Y-228847D01*
X990922Y-231181D01*
X991795Y-232931D01*
X993105Y-234389D01*
X994852Y-234972D01*
X996598Y-234389D01*
X997909Y-232931D01*
X998782Y-231181D01*
X999437Y-228847D01*
X999655Y-226222D01*
X999437Y-223597D01*
X998782Y-221263D01*
X997909Y-219514D01*
X996598Y-218055D01*
X994852Y-217472D01*
G01X1012352Y-234972D02*
X1013880Y-234680D01*
X1015627Y-233806D01*
X1016719Y-232348D01*
X1017155Y-230305D01*
X1016719Y-228264D01*
X1015409Y-226514D01*
X1013444Y-225639D01*
X1011260D01*
X1009950Y-225055D01*
X1008858Y-223597D01*
X1008422Y-221556D01*
X1009077Y-219514D01*
X1010605Y-218055D01*
X1012352Y-217472D01*
X1014098Y-218055D01*
X1015627Y-219514D01*
X1016282Y-221556D01*
X1015845Y-223597D01*
X1014754Y-225055D01*
X1013444Y-225639D01*
X1011260D01*
X1009295Y-226514D01*
X1007985Y-228264D01*
X1007549Y-230305D01*
X1007985Y-232348D01*
X1009077Y-233806D01*
X1010824Y-234680D01*
X1012352Y-234972D01*
G01X1025922Y-235555D02*
X1033782Y-217472D01*
G01X1043204Y-220389D02*
X1044514Y-218639D01*
X1046042Y-217764D01*
X1047789Y-217472D01*
X1049972Y-218055D01*
X1051500Y-219514D01*
X1051937Y-221263D01*
X1051719Y-223014D01*
X1050845Y-224472D01*
X1046479Y-227389D01*
X1044514Y-229430D01*
X1043204Y-232348D01*
X1042767Y-234972D01*
X1051937D01*
G01X1060049Y-232348D02*
X1061358Y-233806D01*
X1062887Y-234680D01*
X1064852Y-234972D01*
X1066817Y-234389D01*
X1068345Y-233222D01*
X1069437Y-231181D01*
X1069655Y-228847D01*
X1069219Y-226514D01*
X1068127Y-225055D01*
X1066598Y-223889D01*
X1065070Y-223597D01*
X1063542Y-223889D01*
X1061577Y-225055D01*
X1062232Y-217472D01*
X1068127D01*
G01X1078422Y-235555D02*
X1086282Y-217472D01*
G01X1095704Y-220389D02*
X1097014Y-218639D01*
X1098542Y-217764D01*
X1100289Y-217472D01*
X1102472Y-218055D01*
X1104000Y-219514D01*
X1104437Y-221263D01*
X1104219Y-223014D01*
X1103345Y-224472D01*
X1098979Y-227389D01*
X1097014Y-229430D01*
X1095704Y-232348D01*
X1095267Y-234972D01*
X1104437D01*
G01X1117352Y-217472D02*
X1115605Y-218055D01*
X1114295Y-219514D01*
X1113422Y-221263D01*
X1112767Y-223597D01*
X1112549Y-226222D01*
X1112767Y-228847D01*
X1113422Y-231181D01*
X1114295Y-232931D01*
X1115605Y-234389D01*
X1117352Y-234972D01*
X1119098Y-234389D01*
X1120409Y-232931D01*
X1121282Y-231181D01*
X1121937Y-228847D01*
X1122155Y-226222D01*
X1121937Y-223597D01*
X1121282Y-221263D01*
X1120409Y-219514D01*
X1119098Y-218055D01*
X1117352Y-217472D01*
G01X1134852Y-234972D02*
Y-217472D01*
X1132232Y-220972D01*
G01Y-234972D02*
X1137472D01*
G01X1148204Y-227681D02*
X1149732Y-225639D01*
X1151042Y-224472D01*
X1152789Y-223889D01*
X1154317Y-224472D01*
X1155409Y-225639D01*
X1156282Y-227389D01*
X1156500Y-229430D01*
X1156282Y-231181D01*
X1155409Y-232931D01*
X1154098Y-234389D01*
X1152570Y-234972D01*
X1150824Y-234389D01*
X1149295Y-232639D01*
X1148422Y-230014D01*
X1148204Y-227097D01*
X1148640Y-223306D01*
X1149295Y-221263D01*
X1150387Y-219222D01*
X1151915Y-217764D01*
X1153444Y-217472D01*
X1154972Y-218055D01*
X1156064Y-219514D01*
G01X1042549Y-189972D02*
Y-172472D01*
X1046915D01*
X1048662Y-173347D01*
X1049972Y-174514D01*
X1051064Y-176263D01*
X1051937Y-178306D01*
X1052155Y-181222D01*
X1051937Y-184139D01*
X1051064Y-186181D01*
X1049972Y-187931D01*
X1048662Y-189097D01*
X1046915Y-189972D01*
X1042549D01*
G01X1068782D02*
Y-178306D01*
G01Y-180347D02*
X1067909Y-179181D01*
X1066598Y-178597D01*
X1065070Y-178306D01*
X1063542Y-178889D01*
X1062232Y-180055D01*
X1061358Y-181805D01*
X1060922Y-184139D01*
X1061358Y-186472D01*
X1062232Y-188222D01*
X1063542Y-189389D01*
X1065070Y-189972D01*
X1066598Y-189680D01*
X1067909Y-188806D01*
X1068782Y-187639D01*
G01X1082352Y-172472D02*
Y-189972D01*
G01X1079295Y-178306D02*
X1085409D01*
G01X1096577Y-182097D02*
X1103564D01*
X1102909Y-180055D01*
X1101817Y-178889D01*
X1100289Y-178306D01*
X1098760Y-178597D01*
X1097450Y-179472D01*
X1096577Y-181514D01*
X1096140Y-183264D01*
Y-185014D01*
X1096577Y-186764D01*
X1097669Y-188514D01*
X1098979Y-189680D01*
X1100507Y-189972D01*
X1102035Y-189389D01*
X1103564Y-187639D01*
M02*
